(kicad_pcb
	(version 20260206)
	(generator "pcbnew")
	(generator_version "10.0")
	(general
		(thickness 1.6)
		(legacy_teardrops no)
	)
	(paper "A4")
	(title_block
		(title "01162023_DA0F0TEBIF0_F0T_Expander_BD_F_brd_V02_OCP.brd")
		(comment 1 "Grand Teton / footprints 4596-4602 of 9728")
	)
	(layers
		(0 "F.Cu" signal "TOP")
		(4 "In1.Cu" signal "GND")
		(6 "In2.Cu" signal "VCC")
		(8 "In3.Cu" signal "VCC1")
		(10 "In4.Cu" signal "GND1")
		(12 "In5.Cu" signal "IN1")
		(14 "In6.Cu" signal "GND2")
		(16 "In7.Cu" signal "IN2")
		(18 "In8.Cu" signal "GND3")
		(20 "In9.Cu" signal "IN3")
		(22 "In10.Cu" signal "GND4")
		(24 "In11.Cu" signal "IN4")
		(26 "In12.Cu" signal "GND5")
		(28 "In13.Cu" signal "IN5")
		(30 "In14.Cu" signal "GND6")
		(32 "In15.Cu" signal "IN6")
		(34 "In16.Cu" signal "GND7")
		(2 "B.Cu" signal "BOTTOM")
		(9 "F.Adhes" user "F.Adhesive")
		(11 "B.Adhes" user "B.Adhesive")
		(13 "F.Paste" user "Package Geometry/Pastemask Top")
		(15 "B.Paste" user "Package Geometry/Pastemask Bottom")
		(5 "F.SilkS" user "Ref Des/Silkscreen Top")
		(7 "B.SilkS" user "Ref Des/Silkscreen Bottom")
		(1 "F.Mask" user "Board Geometry/Soldermask Top")
		(3 "B.Mask" user "Board Geometry/Soldermask Bottom")
		(17 "Dwgs.User" user "User.Drawings")
		(19 "Cmts.User" user "User.Comments")
		(21 "Eco1.User" user "User.Eco1")
		(23 "Eco2.User" user "User.Eco2")
		(25 "Edge.Cuts" user "Board Geometry/Outline")
		(27 "Margin" user)
		(31 "F.CrtYd" user "Package Geometry/Place Bound Top")
		(29 "B.CrtYd" user "Package Geometry/Place Bound Bottom")
		(35 "F.Fab" user "Ref Des/Assembly Top")
		(33 "B.Fab" user "Ref Des/Assembly Bottom")
	)
	(footprint ""
		(layer "F.Cu")
		(at 218.503754 -102.241604 90)
		(property "Reference" "U82"
			(at 0.983996 -2.399284 90)
			(unlocked yes)
			(layer "F.SilkS")
			(effects
				(font
					(size 0.7874 0.5842)
					(thickness 0.1524)
				)
			)
		)
		(property "Value" ""
			(at 0 0 90)
			(layer "F.Fab")
			(effects
				(font
					(size 1.27 1.27)
				)
			)
		)
		(duplicate_pad_numbers_are_jumpers no)
		(fp_line
			(start 1.500124 -1.500124)
			(end 1.500124 -1.004062)
			(stroke
				(width 0.1524)
				(type default)
			)
			(layer "F.SilkS")
		)
		(fp_line
			(start 1.004062 -1.500124)
			(end 1.500124 -1.500124)
			(stroke
				(width 0.1524)
				(type default)
			)
			(layer "F.SilkS")
		)
		(fp_line
			(start -1.500124 -1.500124)
			(end -1.004062 -1.500124)
			(stroke
				(width 0.1524)
				(type default)
			)
			(layer "F.SilkS")
		)
		(fp_line
			(start -1.500124 -1.004062)
			(end -1.500124 -1.500124)
			(stroke
				(width 0.1524)
				(type default)
			)
			(layer "F.SilkS")
		)
		(fp_line
			(start 1.500124 1.004062)
			(end 1.500124 1.500124)
			(stroke
				(width 0.1524)
				(type default)
			)
			(layer "F.SilkS")
		)
		(fp_line
			(start 1.500124 1.500124)
			(end 1.004062 1.500124)
			(stroke
				(width 0.1524)
				(type default)
			)
			(layer "F.SilkS")
		)
		(fp_line
			(start -1.004062 1.500124)
			(end -1.500124 1.500124)
			(stroke
				(width 0.1524)
				(type default)
			)
			(layer "F.SilkS")
		)
		(fp_line
			(start -1.500124 1.500124)
			(end -1.500124 1.004062)
			(stroke
				(width 0.1524)
				(type default)
			)
			(layer "F.SilkS")
		)
		(fp_poly
			(pts
				(xy -2.554986 -0.388366) (xy -1.831848 -0.750062) (xy -2.554986 -1.111504)
			)
			(stroke
				(width 0)
				(type default)
			)
			(fill yes)
			(layer "F.SilkS")
		)
		(fp_line
			(start 1.500124 -1.500124)
			(end 1.500124 1.500124)
			(stroke
				(width 0.1)
				(type default)
			)
			(layer "F.Fab")
		)
		(fp_line
			(start -1.500124 -1.500124)
			(end 1.500124 -1.500124)
			(stroke
				(width 0.1)
				(type default)
			)
			(layer "F.Fab")
		)
		(fp_line
			(start 1.500124 1.500124)
			(end -1.500124 1.500124)
			(stroke
				(width 0.1)
				(type default)
			)
			(layer "F.Fab")
		)
		(fp_line
			(start -1.500124 1.500124)
			(end -1.500124 -1.500124)
			(stroke
				(width 0.1)
				(type default)
			)
			(layer "F.Fab")
		)
		(fp_poly
			(pts
				(xy -2.847848 -1.258062) (xy -2.847848 -0.242062) (xy -1.831848 -0.750062)
			)
			(stroke
				(width 0)
				(type default)
			)
			(fill yes)
			(layer "F.Fab")
		)
		(pad "1" smd rect
			(at -1.400048 -0.750062)
			(size 0.2286 0.6096)
			(layers "F.Cu" "F.Mask" "F.Paste")
			(net "NIC3_ADC_A1")
		)
		(pad "2" smd rect
			(at -1.400048 -0.249936)
			(size 0.2286 0.6096)
			(layers "F.Cu" "F.Mask" "F.Paste")
			(net "NIC3_ADC_A0")
		)
		(pad "3" smd rect
			(at -1.400048 0.249936)
			(size 0.2286 0.6096)
			(layers "F.Cu" "F.Mask" "F.Paste")
			(net "NIC3_ADC_ALERT_N")
		)
		(pad "4" smd rect
			(at -1.400048 0.750062)
			(size 0.2286 0.6096)
			(layers "F.Cu" "F.Mask" "F.Paste")
			(net "SMB_NIC3_ADC_SDA")
		)
		(pad "5" smd rect
			(at -0.750062 1.400048 90)
			(size 0.2286 0.6096)
			(layers "F.Cu" "F.Mask" "F.Paste")
			(net "SMB_NIC3_ADC_SCL")
		)
		(pad "6" smd rect
			(at -0.249936 1.400048 90)
			(size 0.2286 0.6096)
			(layers "F.Cu" "F.Mask" "F.Paste")
			(net "Net_8648")
		)
		(pad "7" smd rect
			(at 0.249936 1.400048 90)
			(size 0.2286 0.6096)
			(layers "F.Cu" "F.Mask" "F.Paste")
			(net "Net_8647")
		)
		(pad "8" smd rect
			(at 0.750062 1.400048 90)
			(size 0.2286 0.6096)
			(layers "F.Cu" "F.Mask" "F.Paste")
			(net "Net_8646")
		)
		(pad "9" smd rect
			(at 1.400048 0.750062)
			(size 0.2286 0.6096)
			(layers "F.Cu" "F.Mask" "F.Paste")
			(net "P3V3_AUX")
		)
		(pad "10" smd rect
			(at 1.400048 0.249936)
			(size 0.2286 0.6096)
			(layers "F.Cu" "F.Mask" "F.Paste")
			(net "GND")
		)
		(pad "11" smd rect
			(at 1.400048 -0.249936)
			(size 0.2286 0.6096)
			(layers "F.Cu" "F.Mask" "F.Paste")
			(net "P12V_NIC3_R")
		)
		(pad "12" smd rect
			(at 1.400048 -0.750062)
			(size 0.2286 0.6096)
			(layers "F.Cu" "F.Mask" "F.Paste")
			(net "P12V_NIC3_VIN_N")
		)
		(pad "13" smd rect
			(at 0.750062 -1.400048 90)
			(size 0.2286 0.6096)
			(layers "F.Cu" "F.Mask" "F.Paste")
			(net "P12V_NIC3_VIN_P")
		)
		(pad "14" smd rect
			(at 0.249936 -1.400048 90)
			(size 0.2286 0.6096)
			(layers "F.Cu" "F.Mask" "F.Paste")
			(net "Net_8645")
		)
		(pad "15" smd rect
			(at -0.249936 -1.400048 90)
			(size 0.2286 0.6096)
			(layers "F.Cu" "F.Mask" "F.Paste")
			(net "Net_8644")
		)
		(pad "16" smd rect
			(at -0.750062 -1.400048 90)
			(size 0.2286 0.6096)
			(layers "F.Cu" "F.Mask" "F.Paste")
			(net "Net_8643")
		)
		(pad "TH" smd rect
			(at 0 0 90)
			(size 1.7018 1.7018)
			(layers "F.Cu" "F.Mask" "F.Paste")
			(net "GND")
		)
		(zone
			(layer "F.Cu")
			(hatch none 0.5)
			(connect_pads
				(clearance 0)
			)
			(min_thickness 0.25)
			(keepout
				(tracks not_allowed)
				(vias allowed)
				(pads allowed)
				(copperpour not_allowed)
				(footprints allowed)
			)
			(placement
				(enabled no)
				(sheetname "")
			)
			(fill
				(thermal_gap 0.5)
				(thermal_bridge_width 0.5)
				(island_removal_mode 0)
			)
			(polygon
				(pts
					(xy 218.478354 -101.197156) (xy 217.459306 -101.197156) (xy 217.459306 -103.286052) (xy 219.548202 -103.286052)
					(xy 219.548202 -101.197156) (xy 218.503754 -101.197156) (xy 218.503754 -101.339904) (xy 219.405454 -101.339904)
					(xy 219.405454 -103.143304) (xy 217.602054 -103.143304) (xy 217.602054 -101.339904) (xy 218.478354 -101.339904)
				)
			)
		)
	)
	(footprint ""
		(layer "F.Cu")
		(at 152.738328 -119.198898)
		(property "Reference" "C258"
			(at 0 0 0)
			(layer "F.SilkS")
			(hide yes)
			(effects
				(font
					(size 1.27 1.27)
				)
			)
		)
		(property "Value" ""
			(at 0 0 0)
			(layer "F.Fab")
			(effects
				(font
					(size 1.27 1.27)
				)
			)
		)
		(duplicate_pad_numbers_are_jumpers no)
		(fp_line
			(start -0.299974 -0.150114)
			(end 0.299974 -0.150114)
			(stroke
				(width 0.1)
				(type default)
			)
			(layer "F.Fab")
		)
		(fp_line
			(start -0.299974 0.150114)
			(end -0.299974 -0.150114)
			(stroke
				(width 0.1)
				(type default)
			)
			(layer "F.Fab")
		)
		(fp_line
			(start 0.299974 -0.150114)
			(end 0.299974 0.150114)
			(stroke
				(width 0.1)
				(type default)
			)
			(layer "F.Fab")
		)
		(fp_line
			(start 0.299974 0.150114)
			(end -0.299974 0.150114)
			(stroke
				(width 0.1)
				(type default)
			)
			(layer "F.Fab")
		)
		(pad "1" smd rect
			(at -0.2667 0)
			(size 0.3048 0.381)
			(layers "F.Cu" "F.Mask" "F.Paste")
			(net "P5E_PEX1_STN1_TX_DP<24>")
		)
		(pad "2" smd rect
			(at 0.2667 0)
			(size 0.3048 0.381)
			(layers "F.Cu" "F.Mask" "F.Paste")
			(net "P5E_PEX1_STN1_TX_C_DP<24>")
		)
	)
	(footprint ""
		(layer "F.Cu")
		(at 278.646382 -58.323734)
		(property "Reference" "PC415"
			(at 0 0 0)
			(layer "F.SilkS")
			(hide yes)
			(effects
				(font
					(size 1.27 1.27)
				)
			)
		)
		(property "Value" ""
			(at 0 0 0)
			(layer "F.Fab")
			(effects
				(font
					(size 1.27 1.27)
				)
			)
		)
		(duplicate_pad_numbers_are_jumpers no)
		(fp_line
			(start -1.524 -0.762)
			(end 1.524 -0.762)
			(stroke
				(width 0.1524)
				(type default)
			)
			(layer "F.SilkS")
		)
		(fp_line
			(start -1.524 0.762)
			(end -1.524 -0.762)
			(stroke
				(width 0.1524)
				(type default)
			)
			(layer "F.SilkS")
		)
		(fp_line
			(start 1.524 -0.762)
			(end 1.524 0.762)
			(stroke
				(width 0.1524)
				(type default)
			)
			(layer "F.SilkS")
		)
		(fp_line
			(start 1.524 0.762)
			(end -1.524 0.762)
			(stroke
				(width 0.1524)
				(type default)
			)
			(layer "F.SilkS")
		)
		(fp_line
			(start -1.1049 -0.724916)
			(end -1.1049 0.724916)
			(stroke
				(width 0.1)
				(type default)
			)
			(layer "F.Fab")
		)
		(fp_line
			(start -1.1049 0.724916)
			(end 1.1049 0.724916)
			(stroke
				(width 0.1)
				(type default)
			)
			(layer "F.Fab")
		)
		(fp_line
			(start 1.1049 -0.724916)
			(end -1.1049 -0.724916)
			(stroke
				(width 0.1)
				(type default)
			)
			(layer "F.Fab")
		)
		(fp_line
			(start 1.1049 0.724916)
			(end 1.1049 -0.724916)
			(stroke
				(width 0.1)
				(type default)
			)
			(layer "F.Fab")
		)
		(pad "1" smd rect
			(at -0.889 0 180)
			(size 1.016 1.27)
			(layers "F.Cu" "F.Mask" "F.Paste")
			(net "GND")
		)
		(pad "2" smd rect
			(at 0.889 0 180)
			(size 1.016 1.27)
			(layers "F.Cu" "F.Mask" "F.Paste")
			(net "P12V_AUX")
		)
	)
	(footprint ""
		(layer "F.Cu")
		(at 196.119242 -150.70455 180)
		(property "Reference" "C218"
			(at 0 0 180)
			(layer "F.SilkS")
			(hide yes)
			(effects
				(font
					(size 1.27 1.27)
				)
			)
		)
		(property "Value" ""
			(at 0 0 180)
			(layer "F.Fab")
			(effects
				(font
					(size 1.27 1.27)
				)
			)
		)
		(duplicate_pad_numbers_are_jumpers no)
		(fp_line
			(start 0.299974 0.150114)
			(end -0.299974 0.150114)
			(stroke
				(width 0.1)
				(type default)
			)
			(layer "F.Fab")
		)
		(fp_line
			(start 0.299974 -0.150114)
			(end 0.299974 0.150114)
			(stroke
				(width 0.1)
				(type default)
			)
			(layer "F.Fab")
		)
		(fp_line
			(start -0.299974 0.150114)
			(end -0.299974 -0.150114)
			(stroke
				(width 0.1)
				(type default)
			)
			(layer "F.Fab")
		)
		(fp_line
			(start -0.299974 -0.150114)
			(end 0.299974 -0.150114)
			(stroke
				(width 0.1)
				(type default)
			)
			(layer "F.Fab")
		)
		(pad "1" smd rect
			(at -0.2667 0 180)
			(size 0.3048 0.381)
			(layers "F.Cu" "F.Mask" "F.Paste")
			(net "P5E_PEX1_STN0_TX_DN<12>")
		)
		(pad "2" smd rect
			(at 0.2667 0 180)
			(size 0.3048 0.381)
			(layers "F.Cu" "F.Mask" "F.Paste")
			(net "P5E_PEX1_STN0_TX_C_DN<12>")
		)
	)
	(footprint ""
		(layer "F.Cu")
		(at 375.632218 -32.848042 90)
		(property "Reference" "PC967"
			(at 0 0 90)
			(layer "F.SilkS")
			(hide yes)
			(effects
				(font
					(size 1.27 1.27)
				)
			)
		)
		(property "Value" ""
			(at 0 0 90)
			(layer "F.Fab")
			(effects
				(font
					(size 1.27 1.27)
				)
			)
		)
		(duplicate_pad_numbers_are_jumpers no)
		(fp_line
			(start 0.7874 -0.4064)
			(end 0.7874 0.4064)
			(stroke
				(width 0.1524)
				(type default)
			)
			(layer "F.SilkS")
		)
		(fp_line
			(start -0.7874 -0.4064)
			(end 0.7874 -0.4064)
			(stroke
				(width 0.1524)
				(type default)
			)
			(layer "F.SilkS")
		)
		(fp_line
			(start 0.7874 0.4064)
			(end -0.7874 0.4064)
			(stroke
				(width 0.1524)
				(type default)
			)
			(layer "F.SilkS")
		)
		(fp_line
			(start -0.7874 0.4064)
			(end -0.7874 -0.4064)
			(stroke
				(width 0.1524)
				(type default)
			)
			(layer "F.SilkS")
		)
		(fp_line
			(start -0.12065 -0.305054)
			(end -0.12065 -0.2794)
			(stroke
				(width 0.1)
				(type default)
			)
			(layer "F.Fab")
		)
		(fp_line
			(start -0.67945 -0.305054)
			(end -0.12065 -0.305054)
			(stroke
				(width 0.1)
				(type default)
			)
			(layer "F.Fab")
		)
		(fp_line
			(start 0.67945 -0.3048)
			(end 0.67945 0.3048)
			(stroke
				(width 0.1)
				(type default)
			)
			(layer "F.Fab")
		)
		(fp_line
			(start 0.12065 -0.3048)
			(end 0.67945 -0.3048)
			(stroke
				(width 0.1)
				(type default)
			)
			(layer "F.Fab")
		)
		(fp_line
			(start 0.12065 -0.2794)
			(end 0.12065 -0.3048)
			(stroke
				(width 0.1)
				(type default)
			)
			(layer "F.Fab")
		)
		(fp_line
			(start -0.12065 -0.2794)
			(end 0.12065 -0.2794)
			(stroke
				(width 0.1)
				(type default)
			)
			(layer "F.Fab")
		)
		(fp_line
			(start 0.120396 0.2794)
			(end -0.12065 0.2794)
			(stroke
				(width 0.1)
				(type default)
			)
			(layer "F.Fab")
		)
		(fp_line
			(start -0.12065 0.2794)
			(end -0.12065 0.3048)
			(stroke
				(width 0.1)
				(type default)
			)
			(layer "F.Fab")
		)
		(fp_line
			(start 0.67945 0.3048)
			(end 0.120396 0.3048)
			(stroke
				(width 0.1)
				(type default)
			)
			(layer "F.Fab")
		)
		(fp_line
			(start 0.120396 0.3048)
			(end 0.120396 0.2794)
			(stroke
				(width 0.1)
				(type default)
			)
			(layer "F.Fab")
		)
		(fp_line
			(start -0.12065 0.3048)
			(end -0.67945 0.3048)
			(stroke
				(width 0.1)
				(type default)
			)
			(layer "F.Fab")
		)
		(fp_line
			(start -0.67945 0.3048)
			(end -0.67945 -0.305054)
			(stroke
				(width 0.1)
				(type default)
			)
			(layer "F.Fab")
		)
		(pad "1" smd circle
			(at -0.40005 0 90)
			(size 0 0)
			(layers "F.Cu" "F.Mask" "F.Paste")
			(net "P3V3_SSD13_CO_DV_DT")
		)
		(pad "2" smd circle
			(at 0.40005 0 90)
			(size 0 0)
			(layers "F.Cu" "F.Mask" "F.Paste")
			(net "GND")
		)
	)
	(footprint ""
		(layer "F.Cu")
		(at 310.224932 -14.735302 180)
		(property "Reference" "C2732"
			(at 0 0 180)
			(layer "F.SilkS")
			(hide yes)
			(effects
				(font
					(size 1.27 1.27)
				)
			)
		)
		(property "Value" ""
			(at 0 0 180)
			(layer "F.Fab")
			(effects
				(font
					(size 1.27 1.27)
				)
			)
		)
		(duplicate_pad_numbers_are_jumpers no)
		(fp_line
			(start 0.7874 0.4064)
			(end -0.7874 0.4064)
			(stroke
				(width 0.1524)
				(type default)
			)
			(layer "F.SilkS")
		)
		(fp_line
			(start 0.7874 -0.4064)
			(end 0.7874 0.4064)
			(stroke
				(width 0.1524)
				(type default)
			)
			(layer "F.SilkS")
		)
		(fp_line
			(start -0.7874 0.4064)
			(end -0.7874 -0.4064)
			(stroke
				(width 0.1524)
				(type default)
			)
			(layer "F.SilkS")
		)
		(fp_line
			(start -0.7874 -0.4064)
			(end 0.7874 -0.4064)
			(stroke
				(width 0.1524)
				(type default)
			)
			(layer "F.SilkS")
		)
		(fp_line
			(start 0.67945 0.3048)
			(end 0.120396 0.3048)
			(stroke
				(width 0.1)
				(type default)
			)
			(layer "F.Fab")
		)
		(fp_line
			(start 0.67945 -0.3048)
			(end 0.67945 0.3048)
			(stroke
				(width 0.1)
				(type default)
			)
			(layer "F.Fab")
		)
		(fp_line
			(start 0.12065 -0.2794)
			(end 0.12065 -0.3048)
			(stroke
				(width 0.1)
				(type default)
			)
			(layer "F.Fab")
		)
		(fp_line
			(start 0.12065 -0.3048)
			(end 0.67945 -0.3048)
			(stroke
				(width 0.1)
				(type default)
			)
			(layer "F.Fab")
		)
		(fp_line
			(start 0.120396 0.3048)
			(end 0.120396 0.2794)
			(stroke
				(width 0.1)
				(type default)
			)
			(layer "F.Fab")
		)
		(fp_line
			(start 0.120396 0.2794)
			(end -0.12065 0.2794)
			(stroke
				(width 0.1)
				(type default)
			)
			(layer "F.Fab")
		)
		(fp_line
			(start -0.12065 0.3048)
			(end -0.67945 0.3048)
			(stroke
				(width 0.1)
				(type default)
			)
			(layer "F.Fab")
		)
		(fp_line
			(start -0.12065 0.2794)
			(end -0.12065 0.3048)
			(stroke
				(width 0.1)
				(type default)
			)
			(layer "F.Fab")
		)
		(fp_line
			(start -0.12065 -0.2794)
			(end 0.12065 -0.2794)
			(stroke
				(width 0.1)
				(type default)
			)
			(layer "F.Fab")
		)
		(fp_line
			(start -0.12065 -0.305054)
			(end -0.12065 -0.2794)
			(stroke
				(width 0.1)
				(type default)
			)
			(layer "F.Fab")
		)
		(fp_line
			(start -0.67945 0.3048)
			(end -0.67945 -0.305054)
			(stroke
				(width 0.1)
				(type default)
			)
			(layer "F.Fab")
		)
		(fp_line
			(start -0.67945 -0.305054)
			(end -0.12065 -0.305054)
			(stroke
				(width 0.1)
				(type default)
			)
			(layer "F.Fab")
		)
		(pad "1" smd circle
			(at -0.40005 0 180)
			(size 0 0)
			(layers "F.Cu" "F.Mask" "F.Paste")
			(net "GND")
		)
		(pad "2" smd circle
			(at 0.40005 0 180)
			(size 0 0)
			(layers "F.Cu" "F.Mask" "F.Paste")
			(net "P3V3_SSD10")
		)
	)
	(footprint ""
		(layer "F.Cu")
		(at 447.676778 -208.504282)
		(property "Reference" "R1000"
			(at 0 0 0)
			(layer "F.SilkS")
			(hide yes)
			(effects
				(font
					(size 1.27 1.27)
				)
			)
		)
		(property "Value" ""
			(at 0 0 0)
			(layer "F.Fab")
			(effects
				(font
					(size 1.27 1.27)
				)
			)
		)
		(duplicate_pad_numbers_are_jumpers no)
		(fp_line
			(start 0.7874 0.4064)
			(end -0.7874 0.4064)
			(stroke
				(width 0.1524)
				(type default)
			)
			(layer "F.SilkS")
		)
		(fp_line
			(start -0.67945 -0.305054)
			(end -0.12065 -0.305054)
			(stroke
				(width 0.1)
				(type default)
			)
			(layer "F.Fab")
		)
		(fp_line
			(start -0.67945 0.3048)
			(end -0.67945 -0.305054)
			(stroke
				(width 0.1)
				(type default)
			)
			(layer "F.Fab")
		)
		(fp_line
			(start -0.12065 -0.305054)
			(end -0.12065 -0.2794)
			(stroke
				(width 0.1)
				(type default)
			)
			(layer "F.Fab")
		)
		(fp_line
			(start -0.12065 -0.2794)
			(end 0.12065 -0.2794)
			(stroke
				(width 0.1)
				(type default)
			)
			(layer "F.Fab")
		)
		(fp_line
			(start -0.12065 0.2794)
			(end -0.12065 0.3048)
			(stroke
				(width 0.1)
				(type default)
			)
			(layer "F.Fab")
		)
		(fp_line
			(start -0.12065 0.3048)
			(end -0.67945 0.3048)
			(stroke
				(width 0.1)
				(type default)
			)
			(layer "F.Fab")
		)
		(fp_line
			(start 0.120396 0.2794)
			(end -0.12065 0.2794)
			(stroke
				(width 0.1)
				(type default)
			)
			(layer "F.Fab")
		)
		(fp_line
			(start 0.120396 0.3048)
			(end 0.120396 0.2794)
			(stroke
				(width 0.1)
				(type default)
			)
			(layer "F.Fab")
		)
		(fp_line
			(start 0.12065 -0.3048)
			(end 0.67945 -0.3048)
			(stroke
				(width 0.1)
				(type default)
			)
			(layer "F.Fab")
		)
		(fp_line
			(start 0.12065 -0.2794)
			(end 0.12065 -0.3048)
			(stroke
				(width 0.1)
				(type default)
			)
			(layer "F.Fab")
		)
		(fp_line
			(start 0.67945 -0.3048)
			(end 0.67945 0.3048)
			(stroke
				(width 0.1)
				(type default)
			)
			(layer "F.Fab")
		)
		(fp_line
			(start 0.67945 0.3048)
			(end 0.120396 0.3048)
			(stroke
				(width 0.1)
				(type default)
			)
			(layer "F.Fab")
		)
		(pad "1" smd circle
			(at -0.40005 0)
			(size 0 0)
			(layers "F.Cu" "F.Mask" "F.Paste")
			(net "USB2_MICRO_DN")
		)
		(pad "2" smd circle
			(at 0.40005 0)
			(size 0 0)
			(layers "F.Cu" "F.Mask" "F.Paste")
			(net "USB2_FT4232_MUX_D_DN")
		)
	)
)
